# S9S_MB_2U (Grand Teton) — schematic netlist excerpt (pin names and nets, part order shuffled) for the footprints in the layout excerpt that follows; sources: Cadence DE-HDL packaged netlist, KiCad conversion of 03242023_DA0F0TMBIJ0_F0T_Motherboard_J_brd_V01_OCP.brd

U2_BL  TP  NA  pkg TP_BOM ONLY  page 312 : TP = NC

R1838  Q_RES_4P_12  0.001 1% CHIP  pkg R2512_4P_H41  page 251
  \1\  = P12V_AUX
  \2\  = P12V_S3_AUX_CPU0_NVDIMM
  \3\  = P12V_AUX_CPU0_DIMM_ISEN_P
  \4\  = P12V_AUX_CPU0_DIMM_ISEN_N

PC429  Q_CAP  3300PF 50V 10% X7R  pkg 0402  page 294 : A = SW_P12V_PVCCINFAON_CPU1_FLT ; B = GND

(kicad_pcb
	(version 20260206)
	(generator "pcbnew")
	(generator_version "10.0")
	(general
		(thickness 1.6)
		(legacy_teardrops no)
	)
	(paper "A4")
	(title_block
		(title "03242023_DA0F0TMBIJ0_F0T_Motherboard_J_brd_V01_OCP.brd")
		(comment 1 "Grand Teton / footprints 1112-1114 of 6105")
	)
	(layers
		(0 "F.Cu" signal "TOP")
		(4 "In1.Cu" signal "GND")
		(6 "In2.Cu" signal "IN1")
		(8 "In3.Cu" signal "GND1")
		(10 "In4.Cu" signal "IN2")
		(12 "In5.Cu" signal "GND2")
		(14 "In6.Cu" signal "IN3")
		(16 "In7.Cu" signal "GND3")
		(18 "In8.Cu" signal "VCC")
		(20 "In9.Cu" signal "VCC1")
		(22 "In10.Cu" signal "GND4")
		(24 "In11.Cu" signal "IN4")
		(26 "In12.Cu" signal "GND5")
		(28 "In13.Cu" signal "IN5")
		(30 "In14.Cu" signal "GND6")
		(32 "In15.Cu" signal "IN6")
		(34 "In16.Cu" signal "GND7")
		(2 "B.Cu" signal "BOTTOM")
		(9 "F.Adhes" user "F.Adhesive")
		(11 "B.Adhes" user "B.Adhesive")
		(13 "F.Paste" user "Package Geometry/Pastemask Top")
		(15 "B.Paste" user "Package Geometry/Pastemask Bottom")
		(5 "F.SilkS" user "Ref Des/Silkscreen Top")
		(7 "B.SilkS" user "Ref Des/Silkscreen Bottom")
		(1 "F.Mask" user "Board Geometry/Soldermask Top")
		(3 "B.Mask" user "Board Geometry/Soldermask Bottom")
		(17 "Dwgs.User" user "User.Drawings")
		(19 "Cmts.User" user "User.Comments")
		(21 "Eco1.User" user "User.Eco1")
		(23 "Eco2.User" user "User.Eco2")
		(25 "Edge.Cuts" user "Board Geometry/Outline")
		(27 "Margin" user)
		(31 "F.CrtYd" user "Package Geometry/Place Bound Top")
		(29 "B.CrtYd" user "Package Geometry/Place Bound Bottom")
		(35 "F.Fab" user "Ref Des/Assembly Top")
		(33 "B.Fab" user "Ref Des/Assembly Bottom")
	)
	(footprint ""
		(layer "F.Cu")
		(at 449.350638 -335.460594 -90)
		(property "Reference" "R1838"
			(at 0 0 270)
			(layer "F.SilkS")
			(hide yes)
			(effects
				(font
					(size 1.27 1.27)
				)
			)
		)
		(property "Value" ""
			(at 0 0 270)
			(layer "F.Fab")
			(effects
				(font
					(size 1.27 1.27)
				)
			)
		)
		(duplicate_pad_numbers_are_jumpers no)
		(fp_line
			(start -4.0386 1.7526)
			(end -4.0386 -1.7526)
			(stroke
				(width 0.1524)
				(type default)
			)
			(layer "F.SilkS")
		)
		(fp_line
			(start 4.0386 1.7526)
			(end -4.0386 1.7526)
			(stroke
				(width 0.1524)
				(type default)
			)
			(layer "F.SilkS")
		)
		(fp_line
			(start -4.0386 -1.7526)
			(end 4.0386 -1.7526)
			(stroke
				(width 0.1524)
				(type default)
			)
			(layer "F.SilkS")
		)
		(fp_line
			(start 4.0386 -1.7526)
			(end 4.0386 1.7526)
			(stroke
				(width 0.1524)
				(type default)
			)
			(layer "F.SilkS")
		)
		(fp_line
			(start -4.0386 1.7526)
			(end -4.0386 -1.7526)
			(stroke
				(width 0.1)
				(type default)
			)
			(layer "F.Fab")
		)
		(fp_line
			(start 4.0386 1.7526)
			(end -4.0386 1.7526)
			(stroke
				(width 0.1)
				(type default)
			)
			(layer "F.Fab")
		)
		(fp_line
			(start -4.0386 -1.7526)
			(end 4.0386 -1.7526)
			(stroke
				(width 0.1)
				(type default)
			)
			(layer "F.Fab")
		)
		(fp_line
			(start 4.0386 -1.7526)
			(end 4.0386 1.7526)
			(stroke
				(width 0.1)
				(type default)
			)
			(layer "F.Fab")
		)
		(pad "1" smd circle
			(at -3.700018 0 180)
			(size 0 0)
			(layers "F.Cu" "F.Mask" "F.Paste")
			(net "P12V_AUX")
		)
		(pad "2" smd circle
			(at 3.700018 0)
			(size 0 0)
			(layers "F.Cu" "F.Mask" "F.Paste")
			(net "P12V_S3_AUX_CPU0_NVDIMM")
		)
		(pad "3" smd rect
			(at -2.70002 0)
			(size 0.4064 1.1176)
			(layers "F.Cu" "F.Mask" "F.Paste")
			(net "P12V_AUX_CPU0_DIMM_ISEN_P")
		)
		(pad "4" smd rect
			(at 2.70002 0)
			(size 0.4064 1.1176)
			(layers "F.Cu" "F.Mask" "F.Paste")
			(net "P12V_AUX_CPU0_DIMM_ISEN_N")
		)
	)
	(footprint ""
		(layer "F.Cu")
		(at 496.64493 -470.91219)
		(property "Reference" "U2_BL"
			(at 0.11049 -3.433318 0)
			(unlocked yes)
			(layer "F.SilkS")
			(effects
				(font
					(size 0.7874 0.5842)
					(thickness 0.1524)
				)
				(justify left)
			)
		)
		(property "Value" ""
			(at 0 0 0)
			(layer "F.Fab")
			(effects
				(font
					(size 1.27 1.27)
				)
			)
		)
		(duplicate_pad_numbers_are_jumpers no)
		(pad "1" smd circle
			(at 0 0)
			(size 0.762 0.762)
			(layers "F.Cu" "F.Mask" "F.Paste")
			(net "Net_8485")
		)
	)
	(footprint ""
		(layer "F.Cu")
		(at 49.648618 -178.060604 90)
		(property "Reference" "PC429"
			(at 0 0 90)
			(layer "F.SilkS")
			(hide yes)
			(effects
				(font
					(size 1.27 1.27)
				)
			)
		)
		(property "Value" ""
			(at 0 0 90)
			(layer "F.Fab")
			(effects
				(font
					(size 1.27 1.27)
				)
			)
		)
		(duplicate_pad_numbers_are_jumpers no)
		(fp_line
			(start 0.7874 -0.4064)
			(end 0.7874 0.4064)
			(stroke
				(width 0.1524)
				(type default)
			)
			(layer "F.SilkS")
		)
		(fp_line
			(start -0.7874 -0.4064)
			(end 0.7874 -0.4064)
			(stroke
				(width 0.1524)
				(type default)
			)
			(layer "F.SilkS")
		)
		(fp_line
			(start 0.7874 0.4064)
			(end -0.7874 0.4064)
			(stroke
				(width 0.1524)
				(type default)
			)
			(layer "F.SilkS")
		)
		(fp_line
			(start -0.7874 0.4064)
			(end -0.7874 -0.4064)
			(stroke
				(width 0.1524)
				(type default)
			)
			(layer "F.SilkS")
		)
		(fp_line
			(start -0.12065 -0.305054)
			(end -0.12065 -0.2794)
			(stroke
				(width 0.1)
				(type default)
			)
			(layer "F.Fab")
		)
		(fp_line
			(start -0.67945 -0.305054)
			(end -0.12065 -0.305054)
			(stroke
				(width 0.1)
				(type default)
			)
			(layer "F.Fab")
		)
		(fp_line
			(start 0.67945 -0.3048)
			(end 0.67945 0.3048)
			(stroke
				(width 0.1)
				(type default)
			)
			(layer "F.Fab")
		)
		(fp_line
			(start 0.12065 -0.3048)
			(end 0.67945 -0.3048)
			(stroke
				(width 0.1)
				(type default)
			)
			(layer "F.Fab")
		)
		(fp_line
			(start 0.12065 -0.2794)
			(end 0.12065 -0.3048)
			(stroke
				(width 0.1)
				(type default)
			)
			(layer "F.Fab")
		)
		(fp_line
			(start -0.12065 -0.2794)
			(end 0.12065 -0.2794)
			(stroke
				(width 0.1)
				(type default)
			)
			(layer "F.Fab")
		)
		(fp_line
			(start 0.120396 0.2794)
			(end -0.12065 0.2794)
			(stroke
				(width 0.1)
				(type default)
			)
			(layer "F.Fab")
		)
		(fp_line
			(start -0.12065 0.2794)
			(end -0.12065 0.3048)
			(stroke
				(width 0.1)
				(type default)
			)
			(layer "F.Fab")
		)
		(fp_line
			(start 0.67945 0.3048)
			(end 0.120396 0.3048)
			(stroke
				(width 0.1)
				(type default)
			)
			(layer "F.Fab")
		)
		(fp_line
			(start 0.120396 0.3048)
			(end 0.120396 0.2794)
			(stroke
				(width 0.1)
				(type default)
			)
			(layer "F.Fab")
		)
		(fp_line
			(start -0.12065 0.3048)
			(end -0.67945 0.3048)
			(stroke
				(width 0.1)
				(type default)
			)
			(layer "F.Fab")
		)
		(fp_line
			(start -0.67945 0.3048)
			(end -0.67945 -0.305054)
			(stroke
				(width 0.1)
				(type default)
			)
			(layer "F.Fab")
		)
		(pad "1" smd circle
			(at -0.40005 0 90)
			(size 0 0)
			(layers "F.Cu" "F.Mask" "F.Paste")
			(net "SW_P12V_PVCCINFAON_CPU1_FLT")
		)
		(pad "2" smd circle
			(at 0.40005 0 90)
			(size 0 0)
			(layers "F.Cu" "F.Mask" "F.Paste")
			(net "GND")
		)
	)
)
